(kicad_pcb
	(version 20260206)
	(generator "pcbnew")
	(generator_version "10.0")
	(general
		(thickness 1.6)
		(legacy_teardrops no)
	)
	(paper "A4")
	(title_block
		(title "12092022_DA0F0TMDCD0_F0T_Management_Board_D_brd_V3_OCP.brd")
		(comment 1 "Grand Teton / footprints 1010-1015 of 1440")
	)
	(layers
		(0 "F.Cu" signal "TOP")
		(4 "In1.Cu" signal "GND")
		(6 "In2.Cu" signal "IN1")
		(8 "In3.Cu" signal "GND1")
		(10 "In4.Cu" signal "IN2")
		(12 "In5.Cu" signal "VCC")
		(14 "In6.Cu" signal "VCC1")
		(16 "In7.Cu" signal "IN3")
		(18 "In8.Cu" signal "GND2")
		(20 "In9.Cu" signal "IN4")
		(22 "In10.Cu" signal "GND3")
		(2 "B.Cu" signal "BOTTOM")
		(9 "F.Adhes" user "F.Adhesive")
		(11 "B.Adhes" user "B.Adhesive")
		(13 "F.Paste" user "Package Geometry/Pastemask Top")
		(15 "B.Paste" user "Package Geometry/Pastemask Bottom")
		(5 "F.SilkS" user "Ref Des/Silkscreen Top")
		(7 "B.SilkS" user "Ref Des/Silkscreen Bottom")
		(1 "F.Mask" user "Board Geometry/Soldermask Top")
		(3 "B.Mask" user "Board Geometry/Soldermask Bottom")
		(17 "Dwgs.User" user "User.Drawings")
		(19 "Cmts.User" user "User.Comments")
		(21 "Eco1.User" user "User.Eco1")
		(23 "Eco2.User" user "User.Eco2")
		(25 "Edge.Cuts" user "Board Geometry/Outline")
		(27 "Margin" user)
		(31 "F.CrtYd" user "Package Geometry/Place Bound Top")
		(29 "B.CrtYd" user "Package Geometry/Place Bound Bottom")
		(35 "F.Fab" user "Ref Des/Assembly Top")
		(33 "B.Fab" user "Ref Des/Assembly Bottom")
	)
	(footprint ""
		(layer "B.Cu")
		(at 58.55208 -61.0616 90)
		(property "Reference" "R37"
			(at 0 0 90)
			(layer "B.SilkS")
			(hide yes)
			(effects
				(font
					(size 1.27 1.27)
				)
				(justify mirror)
			)
		)
		(property "Value" ""
			(at 0 0 90)
			(layer "B.Fab")
			(effects
				(font
					(size 1.27 1.27)
				)
				(justify mirror)
			)
		)
		(duplicate_pad_numbers_are_jumpers no)
		(fp_line
			(start 0.7874 -0.4064)
			(end -0.7874 -0.4064)
			(stroke
				(width 0.1524)
				(type default)
			)
			(layer "B.SilkS")
		)
		(fp_line
			(start -0.7874 -0.4064)
			(end -0.7874 0.4064)
			(stroke
				(width 0.1524)
				(type default)
			)
			(layer "B.SilkS")
		)
		(fp_line
			(start 0.7874 0.4064)
			(end 0.7874 -0.4064)
			(stroke
				(width 0.1524)
				(type default)
			)
			(layer "B.SilkS")
		)
		(fp_line
			(start -0.7874 0.4064)
			(end 0.7874 0.4064)
			(stroke
				(width 0.1524)
				(type default)
			)
			(layer "B.SilkS")
		)
		(fp_line
			(start 0.67945 -0.305054)
			(end 0.12065 -0.305054)
			(stroke
				(width 0.1)
				(type default)
			)
			(layer "B.Fab")
		)
		(fp_line
			(start 0.12065 -0.305054)
			(end 0.12065 -0.2794)
			(stroke
				(width 0.1)
				(type default)
			)
			(layer "B.Fab")
		)
		(fp_line
			(start -0.12065 -0.3048)
			(end -0.67945 -0.3048)
			(stroke
				(width 0.1)
				(type default)
			)
			(layer "B.Fab")
		)
		(fp_line
			(start -0.67945 -0.3048)
			(end -0.67945 0.3048)
			(stroke
				(width 0.1)
				(type default)
			)
			(layer "B.Fab")
		)
		(fp_line
			(start 0.12065 -0.2794)
			(end -0.12065 -0.2794)
			(stroke
				(width 0.1)
				(type default)
			)
			(layer "B.Fab")
		)
		(fp_line
			(start -0.12065 -0.2794)
			(end -0.12065 -0.3048)
			(stroke
				(width 0.1)
				(type default)
			)
			(layer "B.Fab")
		)
		(fp_line
			(start 0.12065 0.2794)
			(end 0.12065 0.3048)
			(stroke
				(width 0.1)
				(type default)
			)
			(layer "B.Fab")
		)
		(fp_line
			(start -0.120396 0.2794)
			(end 0.12065 0.2794)
			(stroke
				(width 0.1)
				(type default)
			)
			(layer "B.Fab")
		)
		(fp_line
			(start 0.67945 0.3048)
			(end 0.67945 -0.305054)
			(stroke
				(width 0.1)
				(type default)
			)
			(layer "B.Fab")
		)
		(fp_line
			(start 0.12065 0.3048)
			(end 0.67945 0.3048)
			(stroke
				(width 0.1)
				(type default)
			)
			(layer "B.Fab")
		)
		(fp_line
			(start -0.120396 0.3048)
			(end -0.120396 0.2794)
			(stroke
				(width 0.1)
				(type default)
			)
			(layer "B.Fab")
		)
		(fp_line
			(start -0.67945 0.3048)
			(end -0.120396 0.3048)
			(stroke
				(width 0.1)
				(type default)
			)
			(layer "B.Fab")
		)
		(pad "1" smd circle
			(at 0.40005 0 270)
			(size 0 0)
			(layers "B.Cu" "B.Mask" "B.Paste")
			(net "IRQ_SMI_ACTIVE_GF_N")
		)
		(pad "2" smd circle
			(at -0.40005 0 270)
			(size 0 0)
			(layers "B.Cu" "B.Mask" "B.Paste")
			(net "IRQ_SMI_ACTIVE_BMC_N")
		)
	)
	(footprint ""
		(layer "B.Cu")
		(at 21.301456 -92.4306 -90)
		(property "Reference" "C242"
			(at 0 0 90)
			(layer "B.SilkS")
			(hide yes)
			(effects
				(font
					(size 1.27 1.27)
				)
				(justify mirror)
			)
		)
		(property "Value" ""
			(at 0 0 90)
			(layer "B.Fab")
			(effects
				(font
					(size 1.27 1.27)
				)
				(justify mirror)
			)
		)
		(duplicate_pad_numbers_are_jumpers no)
		(fp_line
			(start -0.69215 0.2921)
			(end 0.69215 0.2921)
			(stroke
				(width 0.1524)
				(type default)
			)
			(layer "B.SilkS")
		)
		(fp_line
			(start 0.69215 0.2921)
			(end 0.69215 -0.2921)
			(stroke
				(width 0.1524)
				(type default)
			)
			(layer "B.SilkS")
		)
		(fp_line
			(start -0.69215 -0.2921)
			(end -0.69215 0.2921)
			(stroke
				(width 0.1524)
				(type default)
			)
			(layer "B.SilkS")
		)
		(fp_line
			(start 0.69215 -0.2921)
			(end -0.69215 -0.2921)
			(stroke
				(width 0.1524)
				(type default)
			)
			(layer "B.SilkS")
		)
		(fp_line
			(start -0.51435 0.2794)
			(end 0.51435 0.2794)
			(stroke
				(width 0.1)
				(type default)
			)
			(layer "B.Fab")
		)
		(fp_line
			(start 0.51435 0.2794)
			(end 0.51435 -0.2794)
			(stroke
				(width 0.1)
				(type default)
			)
			(layer "B.Fab")
		)
		(fp_line
			(start -0.51435 -0.2794)
			(end -0.51435 0.2794)
			(stroke
				(width 0.1)
				(type default)
			)
			(layer "B.Fab")
		)
		(fp_line
			(start 0.51435 -0.2794)
			(end -0.51435 -0.2794)
			(stroke
				(width 0.1)
				(type default)
			)
			(layer "B.Fab")
		)
		(pad "1" smd circle
			(at 0.40005 0 90)
			(size 0 0)
			(layers "B.Cu" "B.Mask" "B.Paste")
			(net "VCCIO0")
		)
		(pad "2" smd circle
			(at -0.40005 0 90)
			(size 0 0)
			(layers "B.Cu" "B.Mask" "B.Paste")
			(net "GND")
		)
		(zone
			(layer "B.Cu")
			(hatch none 0.5)
			(connect_pads
				(clearance 0)
			)
			(min_thickness 0.25)
			(keepout
				(tracks not_allowed)
				(vias allowed)
				(pads allowed)
				(copperpour not_allowed)
				(footprints allowed)
			)
			(placement
				(enabled no)
				(sheetname "")
			)
			(fill
				(thermal_gap 0.5)
				(thermal_bridge_width 0.5)
				(island_removal_mode 0)
			)
			(polygon
				(pts
					(xy 21.213826 -92.2401) (xy 21.15566 -92.33154) (xy 21.15566 -92.53093) (xy 21.213826 -92.6211)
					(xy 21.389086 -92.6211) (xy 21.447506 -92.53093) (xy 21.447506 -92.33154) (xy 21.38934 -92.2401)
				)
			)
		)
	)
	(footprint ""
		(layer "B.Cu")
		(at 71.374 -19.685 90)
		(property "Reference" "R857"
			(at 0 0 90)
			(layer "B.SilkS")
			(hide yes)
			(effects
				(font
					(size 1.27 1.27)
				)
				(justify mirror)
			)
		)
		(property "Value" ""
			(at 0 0 90)
			(layer "B.Fab")
			(effects
				(font
					(size 1.27 1.27)
				)
				(justify mirror)
			)
		)
		(duplicate_pad_numbers_are_jumpers no)
		(fp_line
			(start 0.7874 -0.4064)
			(end -0.7874 -0.4064)
			(stroke
				(width 0.1524)
				(type default)
			)
			(layer "B.SilkS")
		)
		(fp_line
			(start -0.7874 -0.4064)
			(end -0.7874 0.4064)
			(stroke
				(width 0.1524)
				(type default)
			)
			(layer "B.SilkS")
		)
		(fp_line
			(start 0.7874 0.4064)
			(end 0.7874 -0.4064)
			(stroke
				(width 0.1524)
				(type default)
			)
			(layer "B.SilkS")
		)
		(fp_line
			(start -0.7874 0.4064)
			(end 0.7874 0.4064)
			(stroke
				(width 0.1524)
				(type default)
			)
			(layer "B.SilkS")
		)
		(fp_line
			(start 0.67945 -0.305054)
			(end 0.12065 -0.305054)
			(stroke
				(width 0.1)
				(type default)
			)
			(layer "B.Fab")
		)
		(fp_line
			(start 0.12065 -0.305054)
			(end 0.12065 -0.2794)
			(stroke
				(width 0.1)
				(type default)
			)
			(layer "B.Fab")
		)
		(fp_line
			(start -0.12065 -0.3048)
			(end -0.67945 -0.3048)
			(stroke
				(width 0.1)
				(type default)
			)
			(layer "B.Fab")
		)
		(fp_line
			(start -0.67945 -0.3048)
			(end -0.67945 0.3048)
			(stroke
				(width 0.1)
				(type default)
			)
			(layer "B.Fab")
		)
		(fp_line
			(start 0.12065 -0.2794)
			(end -0.12065 -0.2794)
			(stroke
				(width 0.1)
				(type default)
			)
			(layer "B.Fab")
		)
		(fp_line
			(start -0.12065 -0.2794)
			(end -0.12065 -0.3048)
			(stroke
				(width 0.1)
				(type default)
			)
			(layer "B.Fab")
		)
		(fp_line
			(start 0.12065 0.2794)
			(end 0.12065 0.3048)
			(stroke
				(width 0.1)
				(type default)
			)
			(layer "B.Fab")
		)
		(fp_line
			(start -0.120396 0.2794)
			(end 0.12065 0.2794)
			(stroke
				(width 0.1)
				(type default)
			)
			(layer "B.Fab")
		)
		(fp_line
			(start 0.67945 0.3048)
			(end 0.67945 -0.305054)
			(stroke
				(width 0.1)
				(type default)
			)
			(layer "B.Fab")
		)
		(fp_line
			(start 0.12065 0.3048)
			(end 0.67945 0.3048)
			(stroke
				(width 0.1)
				(type default)
			)
			(layer "B.Fab")
		)
		(fp_line
			(start -0.120396 0.3048)
			(end -0.120396 0.2794)
			(stroke
				(width 0.1)
				(type default)
			)
			(layer "B.Fab")
		)
		(fp_line
			(start -0.67945 0.3048)
			(end -0.120396 0.3048)
			(stroke
				(width 0.1)
				(type default)
			)
			(layer "B.Fab")
		)
		(pad "1" smd circle
			(at 0.40005 0 270)
			(size 0 0)
			(layers "B.Cu" "B.Mask" "B.Paste")
			(net "FM_BOARD_BMC_REV_ID1")
		)
		(pad "2" smd circle
			(at -0.40005 0 270)
			(size 0 0)
			(layers "B.Cu" "B.Mask" "B.Paste")
			(net "GND")
		)
	)
	(footprint ""
		(layer "B.Cu")
		(at 65.89014 -97.6376 180)
		(property "Reference" "R646"
			(at 0 0 0)
			(layer "B.SilkS")
			(hide yes)
			(effects
				(font
					(size 1.27 1.27)
				)
				(justify mirror)
			)
		)
		(property "Value" ""
			(at 0 0 0)
			(layer "B.Fab")
			(effects
				(font
					(size 1.27 1.27)
				)
				(justify mirror)
			)
		)
		(duplicate_pad_numbers_are_jumpers no)
		(fp_line
			(start 1.2954 0.5842)
			(end 1.2954 -0.5842)
			(stroke
				(width 0.1524)
				(type default)
			)
			(layer "B.SilkS")
		)
		(fp_line
			(start 1.2954 -0.5842)
			(end -1.2954 -0.5842)
			(stroke
				(width 0.1524)
				(type default)
			)
			(layer "B.SilkS")
		)
		(fp_line
			(start -1.2954 0.5842)
			(end 1.2954 0.5842)
			(stroke
				(width 0.1524)
				(type default)
			)
			(layer "B.SilkS")
		)
		(fp_line
			(start -1.2954 -0.5842)
			(end -1.2954 0.5842)
			(stroke
				(width 0.1524)
				(type default)
			)
			(layer "B.SilkS")
		)
		(fp_line
			(start 1.1938 0.4064)
			(end 1.1938 -0.406654)
			(stroke
				(width 0.1)
				(type default)
			)
			(layer "B.Fab")
		)
		(fp_line
			(start 1.1938 -0.406654)
			(end 0.8636 -0.406654)
			(stroke
				(width 0.1)
				(type default)
			)
			(layer "B.Fab")
		)
		(fp_line
			(start 0.8636 0.4572)
			(end 0.8636 0.4318)
			(stroke
				(width 0.1)
				(type default)
			)
			(layer "B.Fab")
		)
		(fp_line
			(start 0.8636 0.4318)
			(end 0.8636 0.4064)
			(stroke
				(width 0.1)
				(type default)
			)
			(layer "B.Fab")
		)
		(fp_line
			(start 0.8636 0.4064)
			(end 1.1938 0.4064)
			(stroke
				(width 0.1)
				(type default)
			)
			(layer "B.Fab")
		)
		(fp_line
			(start 0.8636 -0.406654)
			(end 0.8636 -0.4572)
			(stroke
				(width 0.1)
				(type default)
			)
			(layer "B.Fab")
		)
		(fp_line
			(start 0.8636 -0.4572)
			(end -0.8636 -0.4572)
			(stroke
				(width 0.1)
				(type default)
			)
			(layer "B.Fab")
		)
		(fp_line
			(start -0.8636 0.4572)
			(end 0.8636 0.4572)
			(stroke
				(width 0.1)
				(type default)
			)
			(layer "B.Fab")
		)
		(fp_line
			(start -0.8636 0.4064)
			(end -0.8636 0.4572)
			(stroke
				(width 0.1)
				(type default)
			)
			(layer "B.Fab")
		)
		(fp_line
			(start -0.8636 -0.406654)
			(end -1.1938 -0.406654)
			(stroke
				(width 0.1)
				(type default)
			)
			(layer "B.Fab")
		)
		(fp_line
			(start -0.8636 -0.4572)
			(end -0.8636 -0.406654)
			(stroke
				(width 0.1)
				(type default)
			)
			(layer "B.Fab")
		)
		(fp_line
			(start -1.1938 0.4064)
			(end -0.8636 0.4064)
			(stroke
				(width 0.1)
				(type default)
			)
			(layer "B.Fab")
		)
		(fp_line
			(start -1.1938 -0.406654)
			(end -1.1938 0.4064)
			(stroke
				(width 0.1)
				(type default)
			)
			(layer "B.Fab")
		)
		(pad "1" smd rect
			(at 0.7366 0 90)
			(size 0.7112 0.8128)
			(layers "B.Cu" "B.Mask" "B.Paste")
			(net "PGPPA_BMC_AUX_L")
		)
		(pad "2" smd rect
			(at -0.7366 0 90)
			(size 0.7112 0.8128)
			(layers "B.Cu" "B.Mask" "B.Paste")
			(net "P3V3_AUX")
		)
	)
	(footprint ""
		(layer "B.Cu")
		(at 14.224 -24.13 -90)
		(property "Reference" "U8"
			(at 1.31826 1.352296 0)
			(unlocked yes)
			(layer "B.SilkS")
			(effects
				(font
					(size 0.7874 0.5842)
					(thickness 0.1524)
				)
				(justify left mirror)
			)
		)
		(property "Value" ""
			(at 0 0 90)
			(layer "B.Fab")
			(effects
				(font
					(size 1.27 1.27)
				)
				(justify mirror)
			)
		)
		(duplicate_pad_numbers_are_jumpers no)
		(fp_line
			(start -1.400048 1.100074)
			(end 1.400048 1.100074)
			(stroke
				(width 0.1524)
				(type default)
			)
			(layer "B.SilkS")
		)
		(fp_line
			(start 1.400048 1.100074)
			(end 1.400048 -1.100074)
			(stroke
				(width 0.1524)
				(type default)
			)
			(layer "B.SilkS")
		)
		(fp_line
			(start -1.400048 -1.100074)
			(end -1.400048 1.100074)
			(stroke
				(width 0.1524)
				(type default)
			)
			(layer "B.SilkS")
		)
		(fp_line
			(start -1.400048 -1.100074)
			(end 1.400048 -1.100074)
			(stroke
				(width 0.1524)
				(type default)
			)
			(layer "B.SilkS")
		)
		(fp_poly
			(pts
				(xy 1.029208 -1.283716) (xy 0.521208 -2.299716) (xy 1.537208 -2.299716)
			)
			(stroke
				(width 0)
				(type default)
			)
			(fill yes)
			(layer "B.SilkS")
		)
		(fp_line
			(start -0.674878 1.100074)
			(end 0.674878 1.100074)
			(stroke
				(width 0.1)
				(type default)
			)
			(layer "B.Fab")
		)
		(fp_line
			(start 0.674878 1.100074)
			(end 0.674878 -1.100074)
			(stroke
				(width 0.1)
				(type default)
			)
			(layer "B.Fab")
		)
		(fp_line
			(start -0.674878 -1.100074)
			(end -0.674878 1.100074)
			(stroke
				(width 0.1)
				(type default)
			)
			(layer "B.Fab")
		)
		(fp_line
			(start 0.674878 -1.100074)
			(end -0.674878 -1.100074)
			(stroke
				(width 0.1)
				(type default)
			)
			(layer "B.Fab")
		)
		(fp_poly
			(pts
				(xy 1.590548 -0.649986) (xy 2.606548 -1.157986) (xy 2.606548 -0.141986)
			)
			(stroke
				(width 0)
				(type default)
			)
			(fill yes)
			(layer "B.Fab")
		)
		(pad "1" smd rect
			(at 0.94996 -0.649986 180)
			(size 0.4318 0.6096)
			(layers "B.Cu" "B.Mask" "B.Paste")
			(net "BMC_ID_BEEP_SEL")
		)
		(pad "2" smd rect
			(at 0.94996 0 180)
			(size 0.4318 0.6096)
			(layers "B.Cu" "B.Mask" "B.Paste")
			(net "PCH_BEEP_LED")
		)
		(pad "3" smd rect
			(at 0.94996 0.649986 180)
			(size 0.4318 0.6096)
			(layers "B.Cu" "B.Mask" "B.Paste")
			(net "GND")
		)
		(pad "4" smd rect
			(at -0.94996 0.649986 180)
			(size 0.4318 0.6096)
			(layers "B.Cu" "B.Mask" "B.Paste")
			(net "BEEP_LED")
		)
		(pad "5" smd rect
			(at -0.94996 -0.649986 180)
			(size 0.4318 0.6096)
			(layers "B.Cu" "B.Mask" "B.Paste")
			(net "P3V3_AUX")
		)
	)
	(footprint ""
		(layer "B.Cu")
		(at 38.608 -66.421 90)
		(property "Reference" "R642"
			(at 0 0 90)
			(layer "B.SilkS")
			(hide yes)
			(effects
				(font
					(size 1.27 1.27)
				)
				(justify mirror)
			)
		)
		(property "Value" ""
			(at 0 0 90)
			(layer "B.Fab")
			(effects
				(font
					(size 1.27 1.27)
				)
				(justify mirror)
			)
		)
		(duplicate_pad_numbers_are_jumpers no)
		(fp_line
			(start 0.7874 -0.4064)
			(end -0.7874 -0.4064)
			(stroke
				(width 0.1524)
				(type default)
			)
			(layer "B.SilkS")
		)
		(fp_line
			(start -0.7874 -0.4064)
			(end -0.7874 0.4064)
			(stroke
				(width 0.1524)
				(type default)
			)
			(layer "B.SilkS")
		)
		(fp_line
			(start 0.7874 0.4064)
			(end 0.7874 -0.4064)
			(stroke
				(width 0.1524)
				(type default)
			)
			(layer "B.SilkS")
		)
		(fp_line
			(start -0.7874 0.4064)
			(end 0.7874 0.4064)
			(stroke
				(width 0.1524)
				(type default)
			)
			(layer "B.SilkS")
		)
		(fp_line
			(start 0.67945 -0.305054)
			(end 0.12065 -0.305054)
			(stroke
				(width 0.1)
				(type default)
			)
			(layer "B.Fab")
		)
		(fp_line
			(start 0.12065 -0.305054)
			(end 0.12065 -0.2794)
			(stroke
				(width 0.1)
				(type default)
			)
			(layer "B.Fab")
		)
		(fp_line
			(start -0.12065 -0.3048)
			(end -0.67945 -0.3048)
			(stroke
				(width 0.1)
				(type default)
			)
			(layer "B.Fab")
		)
		(fp_line
			(start -0.67945 -0.3048)
			(end -0.67945 0.3048)
			(stroke
				(width 0.1)
				(type default)
			)
			(layer "B.Fab")
		)
		(fp_line
			(start 0.12065 -0.2794)
			(end -0.12065 -0.2794)
			(stroke
				(width 0.1)
				(type default)
			)
			(layer "B.Fab")
		)
		(fp_line
			(start -0.12065 -0.2794)
			(end -0.12065 -0.3048)
			(stroke
				(width 0.1)
				(type default)
			)
			(layer "B.Fab")
		)
		(fp_line
			(start 0.12065 0.2794)
			(end 0.12065 0.3048)
			(stroke
				(width 0.1)
				(type default)
			)
			(layer "B.Fab")
		)
		(fp_line
			(start -0.120396 0.2794)
			(end 0.12065 0.2794)
			(stroke
				(width 0.1)
				(type default)
			)
			(layer "B.Fab")
		)
		(fp_line
			(start 0.67945 0.3048)
			(end 0.67945 -0.305054)
			(stroke
				(width 0.1)
				(type default)
			)
			(layer "B.Fab")
		)
		(fp_line
			(start 0.12065 0.3048)
			(end 0.67945 0.3048)
			(stroke
				(width 0.1)
				(type default)
			)
			(layer "B.Fab")
		)
		(fp_line
			(start -0.120396 0.3048)
			(end -0.120396 0.2794)
			(stroke
				(width 0.1)
				(type default)
			)
			(layer "B.Fab")
		)
		(fp_line
			(start -0.67945 0.3048)
			(end -0.120396 0.3048)
			(stroke
				(width 0.1)
				(type default)
			)
			(layer "B.Fab")
		)
		(pad "1" smd circle
			(at 0.40005 0 270)
			(size 0 0)
			(layers "B.Cu" "B.Mask" "B.Paste")
			(net "GND")
		)
		(pad "2" smd circle
			(at -0.40005 0 270)
			(size 0 0)
			(layers "B.Cu" "B.Mask" "B.Paste")
			(net "FM_JTAG_BMC_MUX_SEL")
		)
	)
)
